# S9S_MB_2U (Grand Teton) — schematic netlist excerpt (pin names and nets, part order shuffled) for the footprints in the layout excerpt that follows; sources: Cadence DE-HDL packaged netlist, KiCad conversion of 03242023_DA0F0TMBIJ0_F0T_Motherboard_J_brd_V01_OCP.brd

PC1217  Q_CAP  22UF 16V 20% X6S  pkg C0805  page 262 : A = SW_P12V_AUX_P1V05_PCH_AUX_FLT ; B = GND
PR1798  Q_RES  3.3 1% CHIP  pkg 0402LF  page 294 : A = SW_PVCCFA_EHV_CPU1_BOOT1 ; B = SW_PVCCFA_EHV_CPU1_BOOT1_R
R3135  Q_RES  1K 1% CHIP  pkg 0402LF  page 162 : A = P3V3_AUX ; B = OCP_V3_2_PRSNT1_R_N

(kicad_pcb
	(version 20260206)
	(generator "pcbnew")
	(generator_version "10.0")
	(general
		(thickness 1.6)
		(legacy_teardrops no)
	)
	(paper "A4")
	(title_block
		(title "03242023_DA0F0TMBIJ0_F0T_Motherboard_J_brd_V01_OCP.brd")
		(comment 1 "Grand Teton / footprints 524-526 of 6105")
	)
	(layers
		(0 "F.Cu" signal "TOP")
		(4 "In1.Cu" signal "GND")
		(6 "In2.Cu" signal "IN1")
		(8 "In3.Cu" signal "GND1")
		(10 "In4.Cu" signal "IN2")
		(12 "In5.Cu" signal "GND2")
		(14 "In6.Cu" signal "IN3")
		(16 "In7.Cu" signal "GND3")
		(18 "In8.Cu" signal "VCC")
		(20 "In9.Cu" signal "VCC1")
		(22 "In10.Cu" signal "GND4")
		(24 "In11.Cu" signal "IN4")
		(26 "In12.Cu" signal "GND5")
		(28 "In13.Cu" signal "IN5")
		(30 "In14.Cu" signal "GND6")
		(32 "In15.Cu" signal "IN6")
		(34 "In16.Cu" signal "GND7")
		(2 "B.Cu" signal "BOTTOM")
		(9 "F.Adhes" user "F.Adhesive")
		(11 "B.Adhes" user "B.Adhesive")
		(13 "F.Paste" user "Package Geometry/Pastemask Top")
		(15 "B.Paste" user "Package Geometry/Pastemask Bottom")
		(5 "F.SilkS" user "Ref Des/Silkscreen Top")
		(7 "B.SilkS" user "Ref Des/Silkscreen Bottom")
		(1 "F.Mask" user "Board Geometry/Soldermask Top")
		(3 "B.Mask" user "Board Geometry/Soldermask Bottom")
		(17 "Dwgs.User" user "User.Drawings")
		(19 "Cmts.User" user "User.Comments")
		(21 "Eco1.User" user "User.Eco1")
		(23 "Eco2.User" user "User.Eco2")
		(25 "Edge.Cuts" user "Board Geometry/Outline")
		(27 "Margin" user)
		(31 "F.CrtYd" user "Package Geometry/Place Bound Top")
		(29 "B.CrtYd" user "Package Geometry/Place Bound Bottom")
		(35 "F.Fab" user "Ref Des/Assembly Top")
		(33 "B.Fab" user "Ref Des/Assembly Bottom")
	)
	(footprint ""
		(layer "F.Cu")
		(at 48.931068 -175.179482 180)
		(property "Reference" "PR1798"
			(at 0 0 180)
			(layer "F.SilkS")
			(hide yes)
			(effects
				(font
					(size 1.27 1.27)
				)
			)
		)
		(property "Value" ""
			(at 0 0 180)
			(layer "F.Fab")
			(effects
				(font
					(size 1.27 1.27)
				)
			)
		)
		(duplicate_pad_numbers_are_jumpers no)
		(fp_line
			(start 0.7874 0.4064)
			(end -0.7874 0.4064)
			(stroke
				(width 0.1524)
				(type default)
			)
			(layer "F.SilkS")
		)
		(fp_line
			(start 0.7874 -0.4064)
			(end 0.7874 0.4064)
			(stroke
				(width 0.1524)
				(type default)
			)
			(layer "F.SilkS")
		)
		(fp_line
			(start -0.7874 0.4064)
			(end -0.7874 -0.4064)
			(stroke
				(width 0.1524)
				(type default)
			)
			(layer "F.SilkS")
		)
		(fp_line
			(start -0.7874 -0.4064)
			(end 0.7874 -0.4064)
			(stroke
				(width 0.1524)
				(type default)
			)
			(layer "F.SilkS")
		)
		(fp_line
			(start 0.67945 0.3048)
			(end 0.120396 0.3048)
			(stroke
				(width 0.1)
				(type default)
			)
			(layer "F.Fab")
		)
		(fp_line
			(start 0.67945 -0.3048)
			(end 0.67945 0.3048)
			(stroke
				(width 0.1)
				(type default)
			)
			(layer "F.Fab")
		)
		(fp_line
			(start 0.12065 -0.2794)
			(end 0.12065 -0.3048)
			(stroke
				(width 0.1)
				(type default)
			)
			(layer "F.Fab")
		)
		(fp_line
			(start 0.12065 -0.3048)
			(end 0.67945 -0.3048)
			(stroke
				(width 0.1)
				(type default)
			)
			(layer "F.Fab")
		)
		(fp_line
			(start 0.120396 0.3048)
			(end 0.120396 0.2794)
			(stroke
				(width 0.1)
				(type default)
			)
			(layer "F.Fab")
		)
		(fp_line
			(start 0.120396 0.2794)
			(end -0.12065 0.2794)
			(stroke
				(width 0.1)
				(type default)
			)
			(layer "F.Fab")
		)
		(fp_line
			(start -0.12065 0.3048)
			(end -0.67945 0.3048)
			(stroke
				(width 0.1)
				(type default)
			)
			(layer "F.Fab")
		)
		(fp_line
			(start -0.12065 0.2794)
			(end -0.12065 0.3048)
			(stroke
				(width 0.1)
				(type default)
			)
			(layer "F.Fab")
		)
		(fp_line
			(start -0.12065 -0.2794)
			(end 0.12065 -0.2794)
			(stroke
				(width 0.1)
				(type default)
			)
			(layer "F.Fab")
		)
		(fp_line
			(start -0.12065 -0.305054)
			(end -0.12065 -0.2794)
			(stroke
				(width 0.1)
				(type default)
			)
			(layer "F.Fab")
		)
		(fp_line
			(start -0.67945 0.3048)
			(end -0.67945 -0.305054)
			(stroke
				(width 0.1)
				(type default)
			)
			(layer "F.Fab")
		)
		(fp_line
			(start -0.67945 -0.305054)
			(end -0.12065 -0.305054)
			(stroke
				(width 0.1)
				(type default)
			)
			(layer "F.Fab")
		)
		(pad "1" smd circle
			(at -0.40005 0 180)
			(size 0 0)
			(layers "F.Cu" "F.Mask" "F.Paste")
			(net "SW_PVCCFA_EHV_CPU1_BOOT1")
		)
		(pad "2" smd circle
			(at 0.40005 0 180)
			(size 0 0)
			(layers "F.Cu" "F.Mask" "F.Paste")
			(net "SW_PVCCFA_EHV_CPU1_BOOT1_R")
		)
	)
	(footprint ""
		(layer "F.Cu")
		(at 20.60956 -75.132692)
		(property "Reference" "R3135"
			(at 0 0 0)
			(layer "F.SilkS")
			(hide yes)
			(effects
				(font
					(size 1.27 1.27)
				)
			)
		)
		(property "Value" ""
			(at 0 0 0)
			(layer "F.Fab")
			(effects
				(font
					(size 1.27 1.27)
				)
			)
		)
		(duplicate_pad_numbers_are_jumpers no)
		(fp_line
			(start -0.7874 -0.4064)
			(end 0.7874 -0.4064)
			(stroke
				(width 0.1524)
				(type default)
			)
			(layer "F.SilkS")
		)
		(fp_line
			(start -0.7874 0.4064)
			(end -0.7874 -0.4064)
			(stroke
				(width 0.1524)
				(type default)
			)
			(layer "F.SilkS")
		)
		(fp_line
			(start 0.7874 -0.4064)
			(end 0.7874 0.4064)
			(stroke
				(width 0.1524)
				(type default)
			)
			(layer "F.SilkS")
		)
		(fp_line
			(start 0.7874 0.4064)
			(end -0.7874 0.4064)
			(stroke
				(width 0.1524)
				(type default)
			)
			(layer "F.SilkS")
		)
		(fp_line
			(start -0.67945 -0.305054)
			(end -0.12065 -0.305054)
			(stroke
				(width 0.1)
				(type default)
			)
			(layer "F.Fab")
		)
		(fp_line
			(start -0.67945 0.3048)
			(end -0.67945 -0.305054)
			(stroke
				(width 0.1)
				(type default)
			)
			(layer "F.Fab")
		)
		(fp_line
			(start -0.12065 -0.305054)
			(end -0.12065 -0.2794)
			(stroke
				(width 0.1)
				(type default)
			)
			(layer "F.Fab")
		)
		(fp_line
			(start -0.12065 -0.2794)
			(end 0.12065 -0.2794)
			(stroke
				(width 0.1)
				(type default)
			)
			(layer "F.Fab")
		)
		(fp_line
			(start -0.12065 0.2794)
			(end -0.12065 0.3048)
			(stroke
				(width 0.1)
				(type default)
			)
			(layer "F.Fab")
		)
		(fp_line
			(start -0.12065 0.3048)
			(end -0.67945 0.3048)
			(stroke
				(width 0.1)
				(type default)
			)
			(layer "F.Fab")
		)
		(fp_line
			(start 0.120396 0.2794)
			(end -0.12065 0.2794)
			(stroke
				(width 0.1)
				(type default)
			)
			(layer "F.Fab")
		)
		(fp_line
			(start 0.120396 0.3048)
			(end 0.120396 0.2794)
			(stroke
				(width 0.1)
				(type default)
			)
			(layer "F.Fab")
		)
		(fp_line
			(start 0.12065 -0.3048)
			(end 0.67945 -0.3048)
			(stroke
				(width 0.1)
				(type default)
			)
			(layer "F.Fab")
		)
		(fp_line
			(start 0.12065 -0.2794)
			(end 0.12065 -0.3048)
			(stroke
				(width 0.1)
				(type default)
			)
			(layer "F.Fab")
		)
		(fp_line
			(start 0.67945 -0.3048)
			(end 0.67945 0.3048)
			(stroke
				(width 0.1)
				(type default)
			)
			(layer "F.Fab")
		)
		(fp_line
			(start 0.67945 0.3048)
			(end 0.120396 0.3048)
			(stroke
				(width 0.1)
				(type default)
			)
			(layer "F.Fab")
		)
		(pad "1" smd circle
			(at -0.40005 0)
			(size 0 0)
			(layers "F.Cu" "F.Mask" "F.Paste")
			(net "P3V3_AUX")
		)
		(pad "2" smd circle
			(at 0.40005 0)
			(size 0 0)
			(layers "F.Cu" "F.Mask" "F.Paste")
			(net "OCP_V3_2_PRSNT1_R_N")
		)
	)
	(footprint ""
		(layer "F.Cu")
		(at 256.14503 -70.40626 -90)
		(property "Reference" "PC1217"
			(at 0 0 270)
			(layer "F.SilkS")
			(hide yes)
			(effects
				(font
					(size 1.27 1.27)
				)
			)
		)
		(property "Value" ""
			(at 0 0 270)
			(layer "F.Fab")
			(effects
				(font
					(size 1.27 1.27)
				)
			)
		)
		(duplicate_pad_numbers_are_jumpers no)
		(fp_line
			(start -1.524 0.762)
			(end -1.524 -0.762)
			(stroke
				(width 0.1524)
				(type default)
			)
			(layer "F.SilkS")
		)
		(fp_line
			(start 1.524 0.762)
			(end -1.524 0.762)
			(stroke
				(width 0.1524)
				(type default)
			)
			(layer "F.SilkS")
		)
		(fp_line
			(start -1.524 -0.762)
			(end 1.524 -0.762)
			(stroke
				(width 0.1524)
				(type default)
			)
			(layer "F.SilkS")
		)
		(fp_line
			(start 1.524 -0.762)
			(end 1.524 0.762)
			(stroke
				(width 0.1524)
				(type default)
			)
			(layer "F.SilkS")
		)
		(fp_line
			(start -1.1049 0.724916)
			(end 1.1049 0.724916)
			(stroke
				(width 0.1)
				(type default)
			)
			(layer "F.Fab")
		)
		(fp_line
			(start 1.1049 0.724916)
			(end 1.1049 -0.724916)
			(stroke
				(width 0.1)
				(type default)
			)
			(layer "F.Fab")
		)
		(fp_line
			(start -1.1049 -0.724916)
			(end -1.1049 0.724916)
			(stroke
				(width 0.1)
				(type default)
			)
			(layer "F.Fab")
		)
		(fp_line
			(start 1.1049 -0.724916)
			(end -1.1049 -0.724916)
			(stroke
				(width 0.1)
				(type default)
			)
			(layer "F.Fab")
		)
		(pad "1" smd rect
			(at -0.889 0 90)
			(size 1.016 1.27)
			(layers "F.Cu" "F.Mask" "F.Paste")
			(net "SW_P12V_AUX_P1V05_PCH_AUX_FLT")
		)
		(pad "2" smd rect
			(at 0.889 0 90)
			(size 1.016 1.27)
			(layers "F.Cu" "F.Mask" "F.Paste")
			(net "GND")
		)
	)
)
